FILE_TYPE = MULTI_PHYS_TABLE;

PART 'CONN_HDR_2X10_M_S_SMT'
CLASS=IO

{========================================================================================}
:CLS_PN             = JEDEC_TYPE                  | ALT_SYMBOLS                   | DESCRIPTION                                                  | CPN_STATUS ;
{========================================================================================}
 'G200-10907-01'    = 'S_M_H_2X10_S_P0787'        | '(S_M_H_2X10_S_P0787)'        | 'CON,20PIN,2X10,2MM PITCH,SMT'                               | ''        
 'G200-11459-01'    = 'S_M_H_2X10_S_P0787_V1'     | '(S_M_H_2X10_S_P0787_V1)'     | 'CON,20PIN,2X10 DUAL,2MM PITCH,HEADER,ROHS,SMT'              | ''        
 'G200-11815-01'    = 'S_M_H_2X10_S_P050_V1'      | '(S_M_H_2X10_S_P050_V1)'      | 'CON,2X10 CL DOUBLE VERTICAL STRIP,1.27MM PITCH,SMT'         | ''        
 'G200-11887-01'    = 'S_M_H_2X10_P100_H394'      | '(S_M_H_2X10_P100_H394)'      | 'CON,20P,2X10,2.54MM,VERT,SMT'                               | ''        
 'A200-00002-JN'    = 'S_M_H_2X10_S_P100_V3'      | '(S_M_H_2X10_S_P100_V3)'      | 'CON,20P,2X10,UNSHROUNDED,320MIL HEAD,SMT'                   | ''        
 'A200-11716-DL'    = 'S_M_H_2X10_NP2_S_P0787_V1' | '(S_M_H_2X10_NP2_S_P0787_V1)' | 'CON,20P,2X10,STACKER HEIGHT 210MM,SMT,TAPE REEL'            | ''        
 'G200-12441-01'    = 'S_M_H_2X10_NP2_S_P100'     | '(S_M_H_2X10_NP2_S_P100)'     | 'CON, HDR, 20P, 2X10, 2.54MM PITCH, SMT'                     | ''        
 'G200-10806-01'    = 'P_M_H_2X10_RA_P0787_V1'    | '(P_M_H_2X10_RA_P0787_V1)'    | 'CONN,20PIN,2X10P,2MM,RA,TH'                                 | ''        
 'G200-11207-01'    = 'P_M_H_2X10_RA_P0787_V2'    | '(P_M_H_2X10_RA_P0787_V2)'    | 'CON,HDR,20P,2X10P,2.00MM,RA,TH'                             | ''        
 'G200-12703-01'    = 'S_M_H_2X10_S_P100_V4'      | '(S_M_H_2X10_S_P100_V4)'      | 'CON,20P,2X10,UNSHR_HDR,VERT,SMT,PITCH 2.54MM'               | ''        
 'G200-12868-01'    = 'S_M_H_2X10_S_P050_V2'      | '(S_M_H_2X10_S_P050_V2)'      | 'CON,2X10PIN,WIRE-TO-BOARD HEADER,1.27MM PITCH,SMD'          | ''        
 'G200-13077-01'    = 'S_M_H_2X10_S_P0197'        | '(S_M_H_2X10_S_P0197)'        | 'CON,20 PINS,2X10,0.5MM PITCH,RECEPTACLE,FPC,VERT,WHITE,SMT' | ''        

END_PART

END.

